(kicad_pcb
	(version 20260206)
	(generator "pcbnew")
	(generator_version "10.0")
	(general
		(thickness 1.6)
		(legacy_teardrops no)
	)
	(paper "A4")
	(title_block
		(title "Wiwynn_Tioga_Pass_MB.brd")
		(comment 1 "Tioga Pass / footprint 190 of 4770 (U2D1), pads 1534-1644 of 3647")
	)
	(layers
		(0 "F.Cu" signal "TOP")
		(4 "In1.Cu" signal "L2GND")
		(6 "In2.Cu" signal "L3")
		(8 "In3.Cu" signal "L4GND")
		(10 "In4.Cu" signal "L5")
		(12 "In5.Cu" signal "L6GND")
		(14 "In6.Cu" signal "L7VCC")
		(16 "In7.Cu" signal "L8VCC")
		(18 "In8.Cu" signal "L9GND")
		(20 "In9.Cu" signal "L10")
		(22 "In10.Cu" signal "L11GND")
		(24 "In11.Cu" signal "L12")
		(26 "In12.Cu" signal "L13GND")
		(2 "B.Cu" signal "BOTTOM")
		(9 "F.Adhes" user "F.Adhesive")
		(11 "B.Adhes" user "B.Adhesive")
		(13 "F.Paste" user "Package Geometry/Pastemask Top")
		(15 "B.Paste" user "Package Geometry/Pastemask Bottom")
		(5 "F.SilkS" user "Ref Des/Silkscreen Top")
		(7 "B.SilkS" user "Ref Des/Silkscreen Bottom")
		(1 "F.Mask" user "Board Geometry/Soldermask Top")
		(3 "B.Mask" user "Board Geometry/Soldermask Bottom")
		(17 "Dwgs.User" user "User.Drawings")
		(19 "Cmts.User" user "User.Comments")
		(21 "Eco1.User" user "User.Eco1")
		(23 "Eco2.User" user "User.Eco2")
		(25 "Edge.Cuts" user "Board Geometry/Outline")
		(27 "Margin" user)
		(31 "F.CrtYd" user "Package Geometry/Place Bound Top")
		(29 "B.CrtYd" user "Package Geometry/Place Bound Bottom")
		(35 "F.Fab" user "Ref Des/Assembly Top")
		(33 "B.Fab" user "Ref Des/Assembly Bottom")
	)
	(footprint ""
		(layer "F.Cu")
		(at 104.99979 -76.550012 180)
		(property "Reference" "U2D1"
			(at 25.19299 30.484318 0)
			(unlocked yes)
			(layer "F.SilkS")
			(effects
				(font
					(size 0.7874 0.5842)
					(thickness 0.1524)
				)
			)
		)
		(property "Value" ""
			(at 0 0 180)
			(layer "F.Fab")
			(effects
				(font
					(size 1.27 1.27)
				)
			)
		)
		(duplicate_pad_numbers_are_jumpers no)
		(pad "CK1" smd custom
			(at -37.250624 9.072372 90)
			(size 0.10795 0.10795)
			(layers "F.Cu" "F.Mask" "F.Paste")
			(net "TP_P3E_CPU1_PE2_RSR_TXP<4>")
			(options
				(clearance outline)
				(anchor circle)
			)
			(primitives
				(gr_poly
					(pts
						(arc
							(start 0.2159 -0.0381)
							(mid 0 -0.254)
							(end -0.2159 -0.0381)
						)
						(arc
							(start -0.2159 0.0381)
							(mid 0 0.254)
							(end 0.2159 0.0381)
						)
					)
					(width 0)
					(fill yes)
				)
			)
		)
		(pad "CK3" smd circle
			(at -35.533584 9.072372)
			(size 0.4318 0.4318)
			(layers "F.Cu" "F.Mask" "F.Paste")
			(net "TP_P3E_CPU1_PE2_RSR_TXP<5>")
		)
		(pad "CK5" smd circle
			(at -33.816544 9.072372)
			(size 0.4318 0.4318)
			(layers "F.Cu" "F.Mask" "F.Paste")
			(net "PVCCIO_CPU1")
		)
		(pad "CK7" smd circle
			(at -32.099504 9.072372)
			(size 0.4318 0.4318)
			(layers "F.Cu" "F.Mask" "F.Paste")
			(net "TP_P3E_CPU1_PE2_RSR_RXN<4>")
		)
		(pad "CK9" smd circle
			(at -30.382464 9.072372)
			(size 0.4318 0.4318)
			(layers "F.Cu" "F.Mask" "F.Paste")
			(net "TP_CPU1_DMI_RX_DN0")
		)
		(pad "CK11" smd circle
			(at -28.665424 9.072372)
			(size 0.4318 0.4318)
			(layers "F.Cu" "F.Mask" "F.Paste")
			(net "GND")
		)
		(pad "CK13" smd circle
			(at -26.948384 9.072372)
			(size 0.4318 0.4318)
			(layers "F.Cu" "F.Mask" "F.Paste")
			(net "TP_CPU1_UPI2_RSVD_DF17")
		)
		(pad "CK15" smd circle
			(at -25.231598 9.072372)
			(size 0.4318 0.4318)
			(layers "F.Cu" "F.Mask" "F.Paste")
			(net "GND")
		)
		(pad "CK17" smd circle
			(at -23.514558 9.072372)
			(size 0.4318 0.4318)
			(layers "F.Cu" "F.Mask" "F.Paste")
			(net "GND")
		)
		(pad "CK19" smd circle
			(at -21.797518 9.072372)
			(size 0.4318 0.4318)
			(layers "F.Cu" "F.Mask" "F.Paste")
			(net "TP_CPU1_RSVD_85")
		)
		(pad "CK21" smd circle
			(at -20.080478 9.072372)
			(size 0.4318 0.4318)
			(layers "F.Cu" "F.Mask" "F.Paste")
			(net "GND")
		)
		(pad "CK23" smd circle
			(at -18.363438 9.072372)
			(size 0.4318 0.4318)
			(layers "F.Cu" "F.Mask" "F.Paste")
			(net "PVCCMCP_CPU1")
		)
		(pad "CK25" smd circle
			(at -16.646398 9.072372)
			(size 0.4318 0.4318)
			(layers "F.Cu" "F.Mask" "F.Paste")
			(net "PVCCMCP_CPU1")
		)
		(pad "CK27" smd circle
			(at -14.929612 9.072372)
			(size 0.4318 0.4318)
			(layers "F.Cu" "F.Mask" "F.Paste")
			(net "GND")
		)
		(pad "CK29" smd circle
			(at -13.212572 9.072372)
			(size 0.4318 0.4318)
			(layers "F.Cu" "F.Mask" "F.Paste")
			(net "A_CPU1_UPI2_RBIAS")
		)
		(pad "CK59" smd circle
			(at 14.071092 7.272274)
			(size 0.508 0.508)
			(layers "F.Cu" "F.Mask" "F.Paste")
			(net "PVCCIN_CPU1")
		)
		(pad "CK61" smd circle
			(at 15.787878 7.272274)
			(size 0.4318 0.4318)
			(layers "F.Cu" "F.Mask" "F.Paste")
			(net "PVCCIN_CPU1")
		)
		(pad "CK63" smd circle
			(at 17.504918 7.272274)
			(size 0.4318 0.4318)
			(layers "F.Cu" "F.Mask" "F.Paste")
			(net "GND")
		)
		(pad "CK65" smd circle
			(at 19.221958 7.272274)
			(size 0.4318 0.4318)
			(layers "F.Cu" "F.Mask" "F.Paste")
			(net "GND")
		)
		(pad "CK67" smd circle
			(at 20.938998 7.272274)
			(size 0.4318 0.4318)
			(layers "F.Cu" "F.Mask" "F.Paste")
			(net "GND")
		)
		(pad "CK69" smd circle
			(at 22.656038 7.272274)
			(size 0.4318 0.4318)
			(layers "F.Cu" "F.Mask" "F.Paste")
			(net "GND")
		)
		(pad "CK71" smd circle
			(at 24.373078 7.272274)
			(size 0.4318 0.4318)
			(layers "F.Cu" "F.Mask" "F.Paste")
			(net "GND")
		)
		(pad "CK73" smd circle
			(at 26.090118 7.272274)
			(size 0.4318 0.4318)
			(layers "F.Cu" "F.Mask" "F.Paste")
			(net "GND")
		)
		(pad "CK75" smd circle
			(at 27.806904 7.272274)
			(size 0.4318 0.4318)
			(layers "F.Cu" "F.Mask" "F.Paste")
			(net "GND")
		)
		(pad "CK77" smd circle
			(at 29.523944 7.272274)
			(size 0.4318 0.4318)
			(layers "F.Cu" "F.Mask" "F.Paste")
			(net "TP_CPU1_RSVD_82")
		)
		(pad "CK79" smd circle
			(at 31.240984 7.272274)
			(size 0.4318 0.4318)
			(layers "F.Cu" "F.Mask" "F.Paste")
			(net "M_L_DQ<4>")
		)
		(pad "CK81" smd circle
			(at 32.958024 7.272274)
			(size 0.4318 0.4318)
			(layers "F.Cu" "F.Mask" "F.Paste")
			(net "M_L_DQ<1>")
		)
		(pad "CK83" smd circle
			(at 34.675064 7.272274)
			(size 0.4318 0.4318)
			(layers "F.Cu" "F.Mask" "F.Paste")
			(net "GND")
		)
		(pad "CK85" smd circle
			(at 36.392104 7.272274)
			(size 0.4318 0.4318)
			(layers "F.Cu" "F.Mask" "F.Paste")
			(net "GND")
		)
		(pad "CL2" smd circle
			(at -36.392104 9.567926)
			(size 0.4318 0.4318)
			(layers "F.Cu" "F.Mask" "F.Paste")
			(net "TP_P3E_CPU1_PE2_RSR_TXN<5>")
		)
		(pad "CL4" smd circle
			(at -34.675064 9.567926)
			(size 0.4318 0.4318)
			(layers "F.Cu" "F.Mask" "F.Paste")
			(net "TP_CPU1_DMI_TX_DP1")
		)
		(pad "CL6" smd circle
			(at -32.958024 9.567926)
			(size 0.4318 0.4318)
			(layers "F.Cu" "F.Mask" "F.Paste")
			(net "TP_P3E_CPU1_PE2_RSR_RXP<3>")
		)
		(pad "CL8" smd circle
			(at -31.240984 9.567926)
			(size 0.4318 0.4318)
			(layers "F.Cu" "F.Mask" "F.Paste")
			(net "GND")
		)
		(pad "CL10" smd circle
			(at -29.523944 9.567926)
			(size 0.4318 0.4318)
			(layers "F.Cu" "F.Mask" "F.Paste")
			(net "TP_CPU1_DMI_RX_DP0")
		)
		(pad "CL12" smd circle
			(at -27.806904 9.567926)
			(size 0.4318 0.4318)
			(layers "F.Cu" "F.Mask" "F.Paste")
			(net "PVCCIO_CPU1")
		)
		(pad "CL14" smd circle
			(at -26.090118 9.567926)
			(size 0.4318 0.4318)
			(layers "F.Cu" "F.Mask" "F.Paste")
			(net "GND")
		)
		(pad "CL16" smd circle
			(at -24.373078 9.567926)
			(size 0.4318 0.4318)
			(layers "F.Cu" "F.Mask" "F.Paste")
			(net "GND")
		)
		(pad "CL18" smd circle
			(at -22.656038 9.567926)
			(size 0.4318 0.4318)
			(layers "F.Cu" "F.Mask" "F.Paste")
			(net "GND")
		)
		(pad "CL20" smd circle
			(at -20.938998 9.567926)
			(size 0.4318 0.4318)
			(layers "F.Cu" "F.Mask" "F.Paste")
			(net "PVCCIO_CPU1")
		)
		(pad "CL22" smd circle
			(at -19.221958 9.567926)
			(size 0.4318 0.4318)
			(layers "F.Cu" "F.Mask" "F.Paste")
			(net "GND")
		)
		(pad "CL24" smd circle
			(at -17.504918 9.567926)
			(size 0.4318 0.4318)
			(layers "F.Cu" "F.Mask" "F.Paste")
			(net "PVCCMCP_CPU1")
		)
		(pad "CL26" smd circle
			(at -15.787878 9.567926)
			(size 0.4318 0.4318)
			(layers "F.Cu" "F.Mask" "F.Paste")
			(net "PVCCMCP_CPU1")
		)
		(pad "CL28" smd circle
			(at -14.071092 9.567926)
			(size 0.4318 0.4318)
			(layers "F.Cu" "F.Mask" "F.Paste")
			(net "A_CPU1_UPI2_RBIAS")
		)
		(pad "CL30" smd circle
			(at -12.354052 9.567926)
			(size 0.4318 0.4318)
			(layers "F.Cu" "F.Mask" "F.Paste")
			(net "A_CPU1_PE012_RBIAS")
		)
		(pad "CL58" smd circle
			(at 13.212572 7.767828)
			(size 0.508 0.508)
			(layers "F.Cu" "F.Mask" "F.Paste")
			(net "PVCCIN_CPU1")
		)
		(pad "CL60" smd circle
			(at 14.929612 7.767828)
			(size 0.4318 0.4318)
			(layers "F.Cu" "F.Mask" "F.Paste")
			(net "PVCCIN_CPU1")
		)
		(pad "CL62" smd circle
			(at 16.646398 7.767828)
			(size 0.4318 0.4318)
			(layers "F.Cu" "F.Mask" "F.Paste")
			(net "GND")
		)
		(pad "CL64" smd circle
			(at 18.363438 7.767828)
			(size 0.4318 0.4318)
			(layers "F.Cu" "F.Mask" "F.Paste")
			(net "GND")
		)
		(pad "CL66" smd circle
			(at 20.080478 7.767828)
			(size 0.4318 0.4318)
			(layers "F.Cu" "F.Mask" "F.Paste")
			(net "GND")
		)
		(pad "CL68" smd circle
			(at 21.797518 7.767828)
			(size 0.4318 0.4318)
			(layers "F.Cu" "F.Mask" "F.Paste")
			(net "M_M_ECC<3>")
		)
		(pad "CL70" smd circle
			(at 23.514558 7.767828)
			(size 0.4318 0.4318)
			(layers "F.Cu" "F.Mask" "F.Paste")
			(net "M_M_DQS_DP<8>")
		)
		(pad "CL72" smd circle
			(at 25.231598 7.767828)
			(size 0.4318 0.4318)
			(layers "F.Cu" "F.Mask" "F.Paste")
			(net "M_M_ECC<5>")
		)
		(pad "CL74" smd circle
			(at 26.948384 7.767828)
			(size 0.4318 0.4318)
			(layers "F.Cu" "F.Mask" "F.Paste")
			(net "GND")
		)
		(pad "CL76" smd circle
			(at 28.665424 7.767828)
			(size 0.4318 0.4318)
			(layers "F.Cu" "F.Mask" "F.Paste")
			(net "GND")
		)
		(pad "CL78" smd circle
			(at 30.382464 7.767828)
			(size 0.4318 0.4318)
			(layers "F.Cu" "F.Mask" "F.Paste")
			(net "GND")
		)
		(pad "CL80" smd circle
			(at 32.099504 7.767828)
			(size 0.4318 0.4318)
			(layers "F.Cu" "F.Mask" "F.Paste")
			(net "GND")
		)
		(pad "CL82" smd circle
			(at 33.816544 7.767828)
			(size 0.4318 0.4318)
			(layers "F.Cu" "F.Mask" "F.Paste")
			(net "M_L_DQS_DN<0>")
		)
		(pad "CL84" smd circle
			(at 35.533584 7.767828)
			(size 0.4318 0.4318)
			(layers "F.Cu" "F.Mask" "F.Paste")
			(net "M_K_DQ<4>")
		)
		(pad "CL86" smd custom
			(at 37.250624 7.767828 270)
			(size 0.10795 0.10795)
			(layers "F.Cu" "F.Mask" "F.Paste")
			(net "M_K_DQ<5>")
			(options
				(clearance outline)
				(anchor circle)
			)
			(primitives
				(gr_poly
					(pts
						(arc
							(start 0.2159 -0.0381)
							(mid 0 -0.254)
							(end -0.2159 -0.0381)
						)
						(arc
							(start -0.2159 0.0381)
							(mid 0 0.254)
							(end 0.2159 0.0381)
						)
					)
					(width 0)
					(fill yes)
				)
			)
		)
		(pad "CM1" smd custom
			(at -37.250624 10.062972 90)
			(size 0.10795 0.10795)
			(layers "F.Cu" "F.Mask" "F.Paste")
			(net "TP_P3E_CPU1_PE2_RSR_TXN<4>")
			(options
				(clearance outline)
				(anchor circle)
			)
			(primitives
				(gr_poly
					(pts
						(arc
							(start 0.2159 -0.0381)
							(mid 0 -0.254)
							(end -0.2159 -0.0381)
						)
						(arc
							(start -0.2159 0.0381)
							(mid 0 0.254)
							(end 0.2159 0.0381)
						)
					)
					(width 0)
					(fill yes)
				)
			)
		)
		(pad "CM3" smd circle
			(at -35.533584 10.062972)
			(size 0.4318 0.4318)
			(layers "F.Cu" "F.Mask" "F.Paste")
			(net "TP_CPU1_DMI_TX_DP2")
		)
		(pad "CM5" smd circle
			(at -33.816544 10.062972)
			(size 0.4318 0.4318)
			(layers "F.Cu" "F.Mask" "F.Paste")
			(net "GND")
		)
		(pad "CM7" smd circle
			(at -32.099504 10.062972)
			(size 0.4318 0.4318)
			(layers "F.Cu" "F.Mask" "F.Paste")
			(net "TP_P3E_CPU1_PE2_RSR_RXN<3>")
		)
		(pad "CM9" smd circle
			(at -30.382464 10.062972)
			(size 0.4318 0.4318)
			(layers "F.Cu" "F.Mask" "F.Paste")
			(net "TP_P3E_CPU1_PE2_RSR_RXP<1>")
		)
		(pad "CM11" smd circle
			(at -28.665424 10.062972)
			(size 0.4318 0.4318)
			(layers "F.Cu" "F.Mask" "F.Paste")
			(net "TP_CPU1_DMI_RX_DN1")
		)
		(pad "CM13" smd circle
			(at -26.948384 10.062972)
			(size 0.4318 0.4318)
			(layers "F.Cu" "F.Mask" "F.Paste")
			(net "TP_CPU1_UPI2_RSVD_DG18")
		)
		(pad "CM15" smd circle
			(at -25.231598 10.062972)
			(size 0.4318 0.4318)
			(layers "F.Cu" "F.Mask" "F.Paste")
			(net "PVCCIO_CPU1")
		)
		(pad "CM19" smd circle
			(at -21.797518 10.062972)
			(size 0.4318 0.4318)
			(layers "F.Cu" "F.Mask" "F.Paste")
			(net "GND")
		)
		(pad "CM21" smd circle
			(at -20.080478 10.062972)
			(size 0.4318 0.4318)
			(layers "F.Cu" "F.Mask" "F.Paste")
			(net "GND")
		)
		(pad "CM23" smd circle
			(at -18.363438 10.062972)
			(size 0.4318 0.4318)
			(layers "F.Cu" "F.Mask" "F.Paste")
			(net "PVCCMCP_CPU1")
		)
		(pad "CM25" smd circle
			(at -16.646398 10.062972)
			(size 0.4318 0.4318)
			(layers "F.Cu" "F.Mask" "F.Paste")
			(net "PVCCMCP_CPU1")
		)
		(pad "CM27" smd circle
			(at -14.929612 10.062972)
			(size 0.4318 0.4318)
			(layers "F.Cu" "F.Mask" "F.Paste")
			(net "GND")
		)
		(pad "CM29" smd circle
			(at -13.212572 10.062972)
			(size 0.4318 0.4318)
			(layers "F.Cu" "F.Mask" "F.Paste")
			(net "GND")
		)
		(pad "CM31" smd circle
			(at -11.495532 10.062972)
			(size 0.4318 0.4318)
			(layers "F.Cu" "F.Mask" "F.Paste")
			(net "GND")
		)
		(pad "CM57" smd circle
			(at 12.354052 8.262874)
			(size 0.508 0.508)
			(layers "F.Cu" "F.Mask" "F.Paste")
			(net "PVCCIN_CPU1")
		)
		(pad "CM59" smd circle
			(at 14.071092 8.262874)
			(size 0.4318 0.4318)
			(layers "F.Cu" "F.Mask" "F.Paste")
			(net "PVCCIN_CPU1")
		)
		(pad "CM61" smd circle
			(at 15.787878 8.262874)
			(size 0.4318 0.4318)
			(layers "F.Cu" "F.Mask" "F.Paste")
			(net "GND")
		)
		(pad "CM63" smd circle
			(at 17.504918 8.262874)
			(size 0.4318 0.4318)
			(layers "F.Cu" "F.Mask" "F.Paste")
			(net "GND")
		)
		(pad "CM65" smd circle
			(at 19.221958 8.262874)
			(size 0.4318 0.4318)
			(layers "F.Cu" "F.Mask" "F.Paste")
			(net "M_M_DQS_DP<12>")
		)
		(pad "CM67" smd circle
			(at 20.938998 8.262874)
			(size 0.4318 0.4318)
			(layers "F.Cu" "F.Mask" "F.Paste")
			(net "GND")
		)
		(pad "CM69" smd circle
			(at 22.656038 8.262874)
			(size 0.4318 0.4318)
			(layers "F.Cu" "F.Mask" "F.Paste")
			(net "M_M_ECC<7>")
		)
		(pad "CM71" smd circle
			(at 24.373078 8.262874)
			(size 0.4318 0.4318)
			(layers "F.Cu" "F.Mask" "F.Paste")
			(net "M_M_ECC<1>")
		)
		(pad "CM73" smd circle
			(at 26.090118 8.262874)
			(size 0.4318 0.4318)
			(layers "F.Cu" "F.Mask" "F.Paste")
			(net "GND")
		)
		(pad "CM75" smd circle
			(at 27.806904 8.262874)
			(size 0.4318 0.4318)
			(layers "F.Cu" "F.Mask" "F.Paste")
			(net "M_M_DQ<5>")
		)
		(pad "CM77" smd circle
			(at 29.523944 8.262874)
			(size 0.4318 0.4318)
			(layers "F.Cu" "F.Mask" "F.Paste")
			(net "GND")
		)
		(pad "CM79" smd circle
			(at 31.240984 8.262874)
			(size 0.4318 0.4318)
			(layers "F.Cu" "F.Mask" "F.Paste")
			(net "M_L_DQ<0>")
		)
		(pad "CM81" smd circle
			(at 32.958024 8.262874)
			(size 0.4318 0.4318)
			(layers "F.Cu" "F.Mask" "F.Paste")
			(net "M_L_DQS_DP<0>")
		)
		(pad "CM83" smd circle
			(at 34.675064 8.262874)
			(size 0.4318 0.4318)
			(layers "F.Cu" "F.Mask" "F.Paste")
			(net "GND")
		)
		(pad "CM85" smd circle
			(at 36.392104 8.262874)
			(size 0.4318 0.4318)
			(layers "F.Cu" "F.Mask" "F.Paste")
			(net "GND")
		)
		(pad "CN2" smd circle
			(at -36.392104 10.558526)
			(size 0.4318 0.4318)
			(layers "F.Cu" "F.Mask" "F.Paste")
			(net "GND")
		)
		(pad "CN4" smd circle
			(at -34.675064 10.558526)
			(size 0.4318 0.4318)
			(layers "F.Cu" "F.Mask" "F.Paste")
			(net "TP_CPU1_DMI_TX_DN2")
		)
		(pad "CN6" smd circle
			(at -32.958024 10.558526)
			(size 0.4318 0.4318)
			(layers "F.Cu" "F.Mask" "F.Paste")
			(net "PVCCIO_CPU1")
		)
		(pad "CN8" smd circle
			(at -31.240984 10.558526)
			(size 0.4318 0.4318)
			(layers "F.Cu" "F.Mask" "F.Paste")
			(net "TP_P3E_CPU1_PE2_RSR_RXP<2>")
		)
		(pad "CN10" smd circle
			(at -29.523944 10.558526)
			(size 0.4318 0.4318)
			(layers "F.Cu" "F.Mask" "F.Paste")
			(net "TP_CPU1_DMI_RX_DP1")
		)
		(pad "CN12" smd circle
			(at -27.806904 10.558526)
			(size 0.4318 0.4318)
			(layers "F.Cu" "F.Mask" "F.Paste")
			(net "GND")
		)
		(pad "CN14" smd circle
			(at -26.090118 10.558526)
			(size 0.4318 0.4318)
			(layers "F.Cu" "F.Mask" "F.Paste")
			(net "GND")
		)
		(pad "CN18" smd circle
			(at -22.656038 10.558526)
			(size 0.4318 0.4318)
			(layers "F.Cu" "F.Mask" "F.Paste")
			(net "GND")
		)
		(pad "CN20" smd circle
			(at -20.938998 10.558526)
			(size 0.4318 0.4318)
			(layers "F.Cu" "F.Mask" "F.Paste")
			(net "GND")
		)
		(pad "CN22" smd circle
			(at -19.221958 10.558526)
			(size 0.4318 0.4318)
			(layers "F.Cu" "F.Mask" "F.Paste")
			(net "TP_CPU1_KTI2_AMONV")
		)
		(pad "CN24" smd circle
			(at -17.504918 10.558526)
			(size 0.4318 0.4318)
			(layers "F.Cu" "F.Mask" "F.Paste")
			(net "PVCCMCP_CPU1")
		)
		(pad "CN26" smd circle
			(at -15.787878 10.558526)
			(size 0.4318 0.4318)
			(layers "F.Cu" "F.Mask" "F.Paste")
			(net "GND")
		)
		(pad "CN28" smd circle
			(at -14.071092 10.558526)
			(size 0.4318 0.4318)
			(layers "F.Cu" "F.Mask" "F.Paste")
			(net "PD_CPU1_MCP01_DMON")
		)
		(pad "CN30" smd circle
			(at -12.354052 10.558526)
			(size 0.4318 0.4318)
			(layers "F.Cu" "F.Mask" "F.Paste")
			(net "A_CPU1_PE012_RBIAS")
		)
		(pad "CN32" smd circle
			(at -10.637012 10.558526)
			(size 0.4318 0.4318)
			(layers "F.Cu" "F.Mask" "F.Paste")
			(net "GND")
		)
		(pad "CN56" smd circle
			(at 11.495532 8.758428)
			(size 0.508 0.508)
			(layers "F.Cu" "F.Mask" "F.Paste")
			(net "PVCCIN_CPU1")
		)
		(pad "CN58" smd circle
			(at 13.212572 8.758428)
			(size 0.4318 0.4318)
			(layers "F.Cu" "F.Mask" "F.Paste")
			(net "PVCCIN_CPU1")
		)
		(pad "CN60" smd circle
			(at 14.929612 8.758428)
			(size 0.4318 0.4318)
			(layers "F.Cu" "F.Mask" "F.Paste")
			(net "GND")
		)
		(pad "CN62" smd circle
			(at 16.646398 8.758428)
			(size 0.4318 0.4318)
			(layers "F.Cu" "F.Mask" "F.Paste")
			(net "GND")
		)
		(pad "CN64" smd circle
			(at 18.363438 8.758428)
			(size 0.4318 0.4318)
			(layers "F.Cu" "F.Mask" "F.Paste")
			(net "M_M_DQ<30>")
		)
		(pad "CN66" smd circle
			(at 20.080478 8.758428)
			(size 0.4318 0.4318)
			(layers "F.Cu" "F.Mask" "F.Paste")
			(net "M_M_DQ<24>")
		)
		(pad "CN68" smd circle
			(at 21.797518 8.758428)
			(size 0.4318 0.4318)
			(layers "F.Cu" "F.Mask" "F.Paste")
			(net "GND")
		)
	)
)
